(kicad_pcb
	(version 20260206)
	(generator "pcbnew")
	(generator_version "10.0")
	(general
		(thickness 1.6)
		(legacy_teardrops no)
	)
	(paper "A4")
	(title_block
		(title "01162023_DA0F0TEBIF0_F0T_Expander_BD_F_brd_V02_OCP.brd")
		(comment 1 "Grand Teton / footprints 9346-9355 of 9728")
	)
	(layers
		(0 "F.Cu" signal "TOP")
		(4 "In1.Cu" signal "GND")
		(6 "In2.Cu" signal "VCC")
		(8 "In3.Cu" signal "VCC1")
		(10 "In4.Cu" signal "GND1")
		(12 "In5.Cu" signal "IN1")
		(14 "In6.Cu" signal "GND2")
		(16 "In7.Cu" signal "IN2")
		(18 "In8.Cu" signal "GND3")
		(20 "In9.Cu" signal "IN3")
		(22 "In10.Cu" signal "GND4")
		(24 "In11.Cu" signal "IN4")
		(26 "In12.Cu" signal "GND5")
		(28 "In13.Cu" signal "IN5")
		(30 "In14.Cu" signal "GND6")
		(32 "In15.Cu" signal "IN6")
		(34 "In16.Cu" signal "GND7")
		(2 "B.Cu" signal "BOTTOM")
		(9 "F.Adhes" user "F.Adhesive")
		(11 "B.Adhes" user "B.Adhesive")
		(13 "F.Paste" user "Package Geometry/Pastemask Top")
		(15 "B.Paste" user "Package Geometry/Pastemask Bottom")
		(5 "F.SilkS" user "Ref Des/Silkscreen Top")
		(7 "B.SilkS" user "Ref Des/Silkscreen Bottom")
		(1 "F.Mask" user "Board Geometry/Soldermask Top")
		(3 "B.Mask" user "Board Geometry/Soldermask Bottom")
		(17 "Dwgs.User" user "User.Drawings")
		(19 "Cmts.User" user "User.Comments")
		(21 "Eco1.User" user "User.Eco1")
		(23 "Eco2.User" user "User.Eco2")
		(25 "Edge.Cuts" user "Board Geometry/Outline")
		(27 "Margin" user)
		(31 "F.CrtYd" user "Package Geometry/Place Bound Top")
		(29 "B.CrtYd" user "Package Geometry/Place Bound Bottom")
		(35 "F.Fab" user "Ref Des/Assembly Top")
		(33 "B.Fab" user "Ref Des/Assembly Bottom")
	)
	(footprint ""
		(layer "B.Cu")
		(at 331.41158 -211.390738)
		(property "Reference" "C2058"
			(at 0 0 0)
			(layer "B.SilkS")
			(hide yes)
			(effects
				(font
					(size 1.27 1.27)
				)
				(justify mirror)
			)
		)
		(property "Value" ""
			(at 0 0 0)
			(layer "B.Fab")
			(effects
				(font
					(size 1.27 1.27)
				)
				(justify mirror)
			)
		)
		(duplicate_pad_numbers_are_jumpers no)
		(fp_line
			(start -0.69215 -0.2921)
			(end -0.69215 0.2921)
			(stroke
				(width 0.1524)
				(type default)
			)
			(layer "B.SilkS")
		)
		(fp_line
			(start -0.69215 0.2921)
			(end 0.69215 0.2921)
			(stroke
				(width 0.1524)
				(type default)
			)
			(layer "B.SilkS")
		)
		(fp_line
			(start 0.69215 -0.2921)
			(end -0.69215 -0.2921)
			(stroke
				(width 0.1524)
				(type default)
			)
			(layer "B.SilkS")
		)
		(fp_line
			(start 0.69215 0.2921)
			(end 0.69215 -0.2921)
			(stroke
				(width 0.1524)
				(type default)
			)
			(layer "B.SilkS")
		)
		(fp_line
			(start -0.51435 -0.2794)
			(end -0.51435 0.2794)
			(stroke
				(width 0.1)
				(type default)
			)
			(layer "B.Fab")
		)
		(fp_line
			(start -0.51435 0.2794)
			(end 0.51435 0.2794)
			(stroke
				(width 0.1)
				(type default)
			)
			(layer "B.Fab")
		)
		(fp_line
			(start 0.51435 -0.2794)
			(end -0.51435 -0.2794)
			(stroke
				(width 0.1)
				(type default)
			)
			(layer "B.Fab")
		)
		(fp_line
			(start 0.51435 0.2794)
			(end 0.51435 -0.2794)
			(stroke
				(width 0.1)
				(type default)
			)
			(layer "B.Fab")
		)
		(pad "1" smd circle
			(at 0.40005 0 180)
			(size 0 0)
			(layers "B.Cu" "B.Mask" "B.Paste")
			(net "P3V3_FPGA_VCCIO2")
		)
		(pad "2" smd circle
			(at -0.40005 0 180)
			(size 0 0)
			(layers "B.Cu" "B.Mask" "B.Paste")
			(net "GND")
		)
		(zone
			(layer "B.Cu")
			(hatch none 0.5)
			(connect_pads
				(clearance 0)
			)
			(min_thickness 0.25)
			(keepout
				(tracks not_allowed)
				(vias allowed)
				(pads allowed)
				(copperpour not_allowed)
				(footprints allowed)
			)
			(placement
				(enabled no)
				(sheetname "")
			)
			(fill
				(thermal_gap 0.5)
				(thermal_bridge_width 0.5)
				(island_removal_mode 0)
			)
			(polygon
				(pts
					(xy 331.60208 -211.303108) (xy 331.51064 -211.244942) (xy 331.31125 -211.244942) (xy 331.22108 -211.303108)
					(xy 331.22108 -211.478368) (xy 331.31125 -211.536788) (xy 331.51064 -211.536788) (xy 331.60208 -211.478622)
				)
			)
		)
	)
	(footprint ""
		(layer "B.Cu")
		(at 44.449746 -293.04996)
		(property "Reference" "C3004"
			(at 0 0 0)
			(layer "B.SilkS")
			(hide yes)
			(effects
				(font
					(size 1.27 1.27)
				)
				(justify mirror)
			)
		)
		(property "Value" ""
			(at 0 0 0)
			(layer "B.Fab")
			(effects
				(font
					(size 1.27 1.27)
				)
				(justify mirror)
			)
		)
		(duplicate_pad_numbers_are_jumpers no)
		(fp_line
			(start -0.299974 -0.150114)
			(end -0.299974 0.150114)
			(stroke
				(width 0.1)
				(type default)
			)
			(layer "B.Fab")
		)
		(fp_line
			(start -0.299974 0.150114)
			(end 0.299974 0.150114)
			(stroke
				(width 0.1)
				(type default)
			)
			(layer "B.Fab")
		)
		(fp_line
			(start 0.299974 -0.150114)
			(end -0.299974 -0.150114)
			(stroke
				(width 0.1)
				(type default)
			)
			(layer "B.Fab")
		)
		(fp_line
			(start 0.299974 0.150114)
			(end 0.299974 -0.150114)
			(stroke
				(width 0.1)
				(type default)
			)
			(layer "B.Fab")
		)
		(pad "1" smd rect
			(at 0.2667 0 180)
			(size 0.3048 0.381)
			(layers "B.Cu" "B.Mask" "B.Paste")
			(net "P1V8_PEX")
		)
		(pad "2" smd rect
			(at -0.2667 0 180)
			(size 0.3048 0.381)
			(layers "B.Cu" "B.Mask" "B.Paste")
			(net "GND")
		)
	)
	(footprint ""
		(layer "B.Cu")
		(at 300.399704 -293.52494 180)
		(property "Reference" "C1613"
			(at 0 0 0)
			(layer "B.SilkS")
			(hide yes)
			(effects
				(font
					(size 1.27 1.27)
				)
				(justify mirror)
			)
		)
		(property "Value" ""
			(at 0 0 0)
			(layer "B.Fab")
			(effects
				(font
					(size 1.27 1.27)
				)
				(justify mirror)
			)
		)
		(duplicate_pad_numbers_are_jumpers no)
		(fp_line
			(start 0.299974 0.150114)
			(end 0.299974 -0.150114)
			(stroke
				(width 0.1)
				(type default)
			)
			(layer "B.Fab")
		)
		(fp_line
			(start 0.299974 -0.150114)
			(end -0.299974 -0.150114)
			(stroke
				(width 0.1)
				(type default)
			)
			(layer "B.Fab")
		)
		(fp_line
			(start -0.299974 0.150114)
			(end 0.299974 0.150114)
			(stroke
				(width 0.1)
				(type default)
			)
			(layer "B.Fab")
		)
		(fp_line
			(start -0.299974 -0.150114)
			(end -0.299974 0.150114)
			(stroke
				(width 0.1)
				(type default)
			)
			(layer "B.Fab")
		)
		(pad "1" smd rect
			(at 0.2667 0)
			(size 0.3048 0.381)
			(layers "B.Cu" "B.Mask" "B.Paste")
			(net "P0V8_PEX2")
		)
		(pad "2" smd rect
			(at -0.2667 0)
			(size 0.3048 0.381)
			(layers "B.Cu" "B.Mask" "B.Paste")
			(net "GND")
		)
	)
	(footprint ""
		(layer "B.Cu")
		(at 76.824078 -114.35207 90)
		(property "Reference" "C869"
			(at 0 0 90)
			(layer "B.SilkS")
			(hide yes)
			(effects
				(font
					(size 1.27 1.27)
				)
				(justify mirror)
			)
		)
		(property "Value" ""
			(at 0 0 90)
			(layer "B.Fab")
			(effects
				(font
					(size 1.27 1.27)
				)
				(justify mirror)
			)
		)
		(duplicate_pad_numbers_are_jumpers no)
		(fp_line
			(start 0.7874 -0.4064)
			(end -0.7874 -0.4064)
			(stroke
				(width 0.1524)
				(type default)
			)
			(layer "B.SilkS")
		)
		(fp_line
			(start -0.7874 -0.4064)
			(end -0.7874 0.4064)
			(stroke
				(width 0.1524)
				(type default)
			)
			(layer "B.SilkS")
		)
		(fp_line
			(start 0.7874 0.4064)
			(end 0.7874 -0.4064)
			(stroke
				(width 0.1524)
				(type default)
			)
			(layer "B.SilkS")
		)
		(fp_line
			(start -0.7874 0.4064)
			(end 0.7874 0.4064)
			(stroke
				(width 0.1524)
				(type default)
			)
			(layer "B.SilkS")
		)
		(fp_line
			(start 0.67945 -0.305054)
			(end 0.12065 -0.305054)
			(stroke
				(width 0.1)
				(type default)
			)
			(layer "B.Fab")
		)
		(fp_line
			(start 0.12065 -0.305054)
			(end 0.12065 -0.2794)
			(stroke
				(width 0.1)
				(type default)
			)
			(layer "B.Fab")
		)
		(fp_line
			(start -0.12065 -0.3048)
			(end -0.67945 -0.3048)
			(stroke
				(width 0.1)
				(type default)
			)
			(layer "B.Fab")
		)
		(fp_line
			(start -0.67945 -0.3048)
			(end -0.67945 0.3048)
			(stroke
				(width 0.1)
				(type default)
			)
			(layer "B.Fab")
		)
		(fp_line
			(start 0.12065 -0.2794)
			(end -0.12065 -0.2794)
			(stroke
				(width 0.1)
				(type default)
			)
			(layer "B.Fab")
		)
		(fp_line
			(start -0.12065 -0.2794)
			(end -0.12065 -0.3048)
			(stroke
				(width 0.1)
				(type default)
			)
			(layer "B.Fab")
		)
		(fp_line
			(start 0.12065 0.2794)
			(end 0.12065 0.3048)
			(stroke
				(width 0.1)
				(type default)
			)
			(layer "B.Fab")
		)
		(fp_line
			(start -0.120396 0.2794)
			(end 0.12065 0.2794)
			(stroke
				(width 0.1)
				(type default)
			)
			(layer "B.Fab")
		)
		(fp_line
			(start 0.67945 0.3048)
			(end 0.67945 -0.305054)
			(stroke
				(width 0.1)
				(type default)
			)
			(layer "B.Fab")
		)
		(fp_line
			(start 0.12065 0.3048)
			(end 0.67945 0.3048)
			(stroke
				(width 0.1)
				(type default)
			)
			(layer "B.Fab")
		)
		(fp_line
			(start -0.120396 0.3048)
			(end -0.120396 0.2794)
			(stroke
				(width 0.1)
				(type default)
			)
			(layer "B.Fab")
		)
		(fp_line
			(start -0.67945 0.3048)
			(end -0.120396 0.3048)
			(stroke
				(width 0.1)
				(type default)
			)
			(layer "B.Fab")
		)
		(pad "1" smd circle
			(at 0.40005 0 270)
			(size 0 0)
			(layers "B.Cu" "B.Mask" "B.Paste")
			(net "P3V3_NIC1")
		)
		(pad "2" smd circle
			(at -0.40005 0 270)
			(size 0 0)
			(layers "B.Cu" "B.Mask" "B.Paste")
			(net "GND")
		)
	)
	(footprint ""
		(layer "B.Cu")
		(at 240.461038 -218.610434 180)
		(property "Reference" "C3612"
			(at 0 0 0)
			(layer "B.SilkS")
			(hide yes)
			(effects
				(font
					(size 1.27 1.27)
				)
				(justify mirror)
			)
		)
		(property "Value" ""
			(at 0 0 0)
			(layer "B.Fab")
			(effects
				(font
					(size 1.27 1.27)
				)
				(justify mirror)
			)
		)
		(duplicate_pad_numbers_are_jumpers no)
		(fp_line
			(start 0.69215 0.2921)
			(end 0.69215 -0.2921)
			(stroke
				(width 0.1524)
				(type default)
			)
			(layer "B.SilkS")
		)
		(fp_line
			(start 0.69215 -0.2921)
			(end -0.69215 -0.2921)
			(stroke
				(width 0.1524)
				(type default)
			)
			(layer "B.SilkS")
		)
		(fp_line
			(start -0.69215 0.2921)
			(end 0.69215 0.2921)
			(stroke
				(width 0.1524)
				(type default)
			)
			(layer "B.SilkS")
		)
		(fp_line
			(start -0.69215 -0.2921)
			(end -0.69215 0.2921)
			(stroke
				(width 0.1524)
				(type default)
			)
			(layer "B.SilkS")
		)
		(fp_line
			(start 0.51435 0.2794)
			(end 0.51435 -0.2794)
			(stroke
				(width 0.1)
				(type default)
			)
			(layer "B.Fab")
		)
		(fp_line
			(start 0.51435 -0.2794)
			(end -0.51435 -0.2794)
			(stroke
				(width 0.1)
				(type default)
			)
			(layer "B.Fab")
		)
		(fp_line
			(start -0.51435 0.2794)
			(end 0.51435 0.2794)
			(stroke
				(width 0.1)
				(type default)
			)
			(layer "B.Fab")
		)
		(fp_line
			(start -0.51435 -0.2794)
			(end -0.51435 0.2794)
			(stroke
				(width 0.1)
				(type default)
			)
			(layer "B.Fab")
		)
		(pad "1" smd circle
			(at 0.40005 0)
			(size 0 0)
			(layers "B.Cu" "B.Mask" "B.Paste")
			(net "P1V2_BIC_ADCVREFREXT0")
		)
		(pad "2" smd circle
			(at -0.40005 0)
			(size 0 0)
			(layers "B.Cu" "B.Mask" "B.Paste")
			(net "GND")
		)
		(zone
			(layer "B.Cu")
			(hatch none 0.5)
			(connect_pads
				(clearance 0)
			)
			(min_thickness 0.25)
			(keepout
				(tracks not_allowed)
				(vias allowed)
				(pads allowed)
				(copperpour not_allowed)
				(footprints allowed)
			)
			(placement
				(enabled no)
				(sheetname "")
			)
			(fill
				(thermal_gap 0.5)
				(thermal_bridge_width 0.5)
				(island_removal_mode 0)
			)
			(polygon
				(pts
					(xy 240.270538 -218.698064) (xy 240.361978 -218.75623) (xy 240.561368 -218.75623) (xy 240.651538 -218.698064)
					(xy 240.651538 -218.522804) (xy 240.561368 -218.464384) (xy 240.361978 -218.464384) (xy 240.270538 -218.52255)
				)
			)
		)
	)
	(footprint ""
		(layer "B.Cu")
		(at 287.145476 -296.37482)
		(property "Reference" "C1636"
			(at 0 0 0)
			(layer "B.SilkS")
			(hide yes)
			(effects
				(font
					(size 1.27 1.27)
				)
				(justify mirror)
			)
		)
		(property "Value" ""
			(at 0 0 0)
			(layer "B.Fab")
			(effects
				(font
					(size 1.27 1.27)
				)
				(justify mirror)
			)
		)
		(duplicate_pad_numbers_are_jumpers no)
		(fp_line
			(start -0.299974 -0.150114)
			(end -0.299974 0.150114)
			(stroke
				(width 0.1)
				(type default)
			)
			(layer "B.Fab")
		)
		(fp_line
			(start -0.299974 0.150114)
			(end 0.299974 0.150114)
			(stroke
				(width 0.1)
				(type default)
			)
			(layer "B.Fab")
		)
		(fp_line
			(start 0.299974 -0.150114)
			(end -0.299974 -0.150114)
			(stroke
				(width 0.1)
				(type default)
			)
			(layer "B.Fab")
		)
		(fp_line
			(start 0.299974 0.150114)
			(end 0.299974 -0.150114)
			(stroke
				(width 0.1)
				(type default)
			)
			(layer "B.Fab")
		)
		(pad "1" smd rect
			(at 0.2667 0 180)
			(size 0.3048 0.381)
			(layers "B.Cu" "B.Mask" "B.Paste")
			(net "P0V8_PEX2")
		)
		(pad "2" smd rect
			(at -0.2667 0 180)
			(size 0.3048 0.381)
			(layers "B.Cu" "B.Mask" "B.Paste")
			(net "GND")
		)
	)
	(footprint ""
		(layer "B.Cu")
		(at 9.142984 -274.99183 180)
		(property "Reference" "C4236"
			(at 0 0 0)
			(layer "B.SilkS")
			(hide yes)
			(effects
				(font
					(size 1.27 1.27)
				)
				(justify mirror)
			)
		)
		(property "Value" ""
			(at 0 0 0)
			(layer "B.Fab")
			(effects
				(font
					(size 1.27 1.27)
				)
				(justify mirror)
			)
		)
		(duplicate_pad_numbers_are_jumpers no)
		(fp_line
			(start 0.299974 0.150114)
			(end 0.299974 -0.150114)
			(stroke
				(width 0.1)
				(type default)
			)
			(layer "B.Fab")
		)
		(fp_line
			(start 0.299974 -0.150114)
			(end -0.299974 -0.150114)
			(stroke
				(width 0.1)
				(type default)
			)
			(layer "B.Fab")
		)
		(fp_line
			(start -0.299974 0.150114)
			(end 0.299974 0.150114)
			(stroke
				(width 0.1)
				(type default)
			)
			(layer "B.Fab")
		)
		(fp_line
			(start -0.299974 -0.150114)
			(end -0.299974 0.150114)
			(stroke
				(width 0.1)
				(type default)
			)
			(layer "B.Fab")
		)
		(pad "1" smd rect
			(at 0.2667 0)
			(size 0.3048 0.381)
			(layers "B.Cu" "B.Mask" "B.Paste")
			(net "P1V25_PEX0")
		)
		(pad "2" smd rect
			(at -0.2667 0)
			(size 0.3048 0.381)
			(layers "B.Cu" "B.Mask" "B.Paste")
			(net "GND")
		)
	)
	(footprint ""
		(layer "B.Cu")
		(at 164.824918 -293.99992 90)
		(property "Reference" "C1368"
			(at 0 0 90)
			(layer "B.SilkS")
			(hide yes)
			(effects
				(font
					(size 1.27 1.27)
				)
				(justify mirror)
			)
		)
		(property "Value" ""
			(at 0 0 90)
			(layer "B.Fab")
			(effects
				(font
					(size 1.27 1.27)
				)
				(justify mirror)
			)
		)
		(duplicate_pad_numbers_are_jumpers no)
		(fp_line
			(start 0.299974 -0.150114)
			(end -0.299974 -0.150114)
			(stroke
				(width 0.1)
				(type default)
			)
			(layer "B.Fab")
		)
		(fp_line
			(start -0.299974 -0.150114)
			(end -0.299974 0.150114)
			(stroke
				(width 0.1)
				(type default)
			)
			(layer "B.Fab")
		)
		(fp_line
			(start 0.299974 0.150114)
			(end 0.299974 -0.150114)
			(stroke
				(width 0.1)
				(type default)
			)
			(layer "B.Fab")
		)
		(fp_line
			(start -0.299974 0.150114)
			(end 0.299974 0.150114)
			(stroke
				(width 0.1)
				(type default)
			)
			(layer "B.Fab")
		)
		(pad "1" smd rect
			(at 0.2667 0 270)
			(size 0.3048 0.381)
			(layers "B.Cu" "B.Mask" "B.Paste")
			(net "P0V8_PEX1")
		)
		(pad "2" smd rect
			(at -0.2667 0 270)
			(size 0.3048 0.381)
			(layers "B.Cu" "B.Mask" "B.Paste")
			(net "GND")
		)
	)
	(footprint ""
		(layer "B.Cu")
		(at 401.930108 -295.221914)
		(property "Reference" "C1866"
			(at 0 0 0)
			(layer "B.SilkS")
			(hide yes)
			(effects
				(font
					(size 1.27 1.27)
				)
				(justify mirror)
			)
		)
		(property "Value" ""
			(at 0 0 0)
			(layer "B.Fab")
			(effects
				(font
					(size 1.27 1.27)
				)
				(justify mirror)
			)
		)
		(duplicate_pad_numbers_are_jumpers no)
		(fp_line
			(start -1.2954 -0.5842)
			(end -1.2954 0.5842)
			(stroke
				(width 0.1524)
				(type default)
			)
			(layer "B.SilkS")
		)
		(fp_line
			(start -1.2954 0.5842)
			(end 1.2954 0.5842)
			(stroke
				(width 0.1524)
				(type default)
			)
			(layer "B.SilkS")
		)
		(fp_line
			(start 1.2954 -0.5842)
			(end -1.2954 -0.5842)
			(stroke
				(width 0.1524)
				(type default)
			)
			(layer "B.SilkS")
		)
		(fp_line
			(start 1.2954 0.5842)
			(end 1.2954 -0.5842)
			(stroke
				(width 0.1524)
				(type default)
			)
			(layer "B.SilkS")
		)
		(fp_line
			(start -1.1938 -0.4064)
			(end -1.1938 0.4064)
			(stroke
				(width 0.1)
				(type default)
			)
			(layer "B.Fab")
		)
		(fp_line
			(start -1.1938 0.4064)
			(end -0.8636 0.4064)
			(stroke
				(width 0.1)
				(type default)
			)
			(layer "B.Fab")
		)
		(fp_line
			(start -0.8636 -0.4572)
			(end -0.8636 -0.4064)
			(stroke
				(width 0.1)
				(type default)
			)
			(layer "B.Fab")
		)
		(fp_line
			(start -0.8636 -0.4064)
			(end -1.1938 -0.4064)
			(stroke
				(width 0.1)
				(type default)
			)
			(layer "B.Fab")
		)
		(fp_line
			(start -0.8636 0.4064)
			(end -0.8636 0.4572)
			(stroke
				(width 0.1)
				(type default)
			)
			(layer "B.Fab")
		)
		(fp_line
			(start -0.8636 0.4572)
			(end 0.8636 0.4572)
			(stroke
				(width 0.1)
				(type default)
			)
			(layer "B.Fab")
		)
		(fp_line
			(start 0.8636 -0.4572)
			(end -0.8636 -0.4572)
			(stroke
				(width 0.1)
				(type default)
			)
			(layer "B.Fab")
		)
		(fp_line
			(start 0.8636 -0.4064)
			(end 0.8636 -0.4572)
			(stroke
				(width 0.1)
				(type default)
			)
			(layer "B.Fab")
		)
		(fp_line
			(start 0.8636 0.4064)
			(end 1.1938 0.4064)
			(stroke
				(width 0.1)
				(type default)
			)
			(layer "B.Fab")
		)
		(fp_line
			(start 0.8636 0.4572)
			(end 0.8636 0.4064)
			(stroke
				(width 0.1)
				(type default)
			)
			(layer "B.Fab")
		)
		(fp_line
			(start 1.1938 -0.4064)
			(end 0.8636 -0.4064)
			(stroke
				(width 0.1)
				(type default)
			)
			(layer "B.Fab")
		)
		(fp_line
			(start 1.1938 0.4064)
			(end 1.1938 -0.4064)
			(stroke
				(width 0.1)
				(type default)
			)
			(layer "B.Fab")
		)
		(pad "1" smd rect
			(at 0.7366 0 270)
			(size 0.7112 0.8128)
			(layers "B.Cu" "B.Mask" "B.Paste")
			(net "P0V8_PEX3")
		)
		(pad "2" smd rect
			(at -0.7366 0 270)
			(size 0.7112 0.8128)
			(layers "B.Cu" "B.Mask" "B.Paste")
			(net "GND")
		)
	)
	(footprint ""
		(layer "B.Cu")
		(at 170.999912 -303.499774 -90)
		(property "Reference" "C3078"
			(at 0 0 90)
			(layer "B.SilkS")
			(hide yes)
			(effects
				(font
					(size 1.27 1.27)
				)
				(justify mirror)
			)
		)
		(property "Value" ""
			(at 0 0 90)
			(layer "B.Fab")
			(effects
				(font
					(size 1.27 1.27)
				)
				(justify mirror)
			)
		)
		(duplicate_pad_numbers_are_jumpers no)
		(fp_line
			(start -0.299974 0.150114)
			(end 0.299974 0.150114)
			(stroke
				(width 0.1)
				(type default)
			)
			(layer "B.Fab")
		)
		(fp_line
			(start 0.299974 0.150114)
			(end 0.299974 -0.150114)
			(stroke
				(width 0.1)
				(type default)
			)
			(layer "B.Fab")
		)
		(fp_line
			(start -0.299974 -0.150114)
			(end -0.299974 0.150114)
			(stroke
				(width 0.1)
				(type default)
			)
			(layer "B.Fab")
		)
		(fp_line
			(start 0.299974 -0.150114)
			(end -0.299974 -0.150114)
			(stroke
				(width 0.1)
				(type default)
			)
			(layer "B.Fab")
		)
		(pad "1" smd rect
			(at 0.2667 0 90)
			(size 0.3048 0.381)
			(layers "B.Cu" "B.Mask" "B.Paste")
			(net "P1V25_PEX1")
		)
		(pad "2" smd rect
			(at -0.2667 0 90)
			(size 0.3048 0.381)
			(layers "B.Cu" "B.Mask" "B.Paste")
			(net "GND")
		)
	)
)
